%FSTAX25Y25*%
%MOIN*%
%SFA1B1*%

%IPPOS*%
%ADD21C,0.009000*%
%ADD136R,1.389760X0.216540*%
%LNtimecard-dc-beta-v1-1*%
%LPD*%
G36*
X0700787Y0059055D02*
X0673228D01*
Y0080709*
X0700787*
Y0059055*
G37*
%LNtimecard-dc-beta-v1-2*%
%LPC*%
G36*
X0686418Y0073827D02*
X0685114D01*
X0680075Y0066276*
Y0073827*
X0678854*
Y0064222*
X0680172*
X0685197Y0071759*
Y0064222*
X0686418*
Y0073827*
G37*
G36*
X0692054Y0073993D02*
X0691873D01*
X0691776Y0073979*
X0691679*
X0691415Y0073952*
X0691124Y007391*
X0690818Y007384*
X0690485Y0073757*
X069018Y0073646*
X0690166*
X0690138Y0073632*
X0690097Y0073605*
X0690041Y0073577*
X0689902Y0073507*
X0689722Y0073383*
X0689514Y0073244*
X0689305Y0073063*
X0689111Y0072855*
X0688931Y0072619*
Y0072605*
X0688917Y0072591*
X0688889Y007255*
X0688861Y0072508*
X0688792Y0072369*
X0688709Y0072189*
X0688611Y0071967*
X0688542Y0071703*
X0688473Y0071425*
X0688445Y007112*
X0689666Y0071023*
Y0071037*
Y0071065*
X068968Y0071106*
X0689694Y0071176*
X0689736Y0071328*
X0689791Y0071536*
X0689875Y0071759*
X0689999Y0071981*
X0690152Y0072189*
X0690346Y0072383*
X0690374Y0072397*
X0690444Y0072452*
X0690582Y0072536*
X0690763Y0072619*
X0690999Y0072702*
X0691276Y0072786*
X0691623Y0072841*
X0692012Y0072855*
X0692206*
X069229Y0072841*
X0692401Y0072827*
X0692651Y0072799*
X0692928Y0072744*
X0693206Y0072675*
X0693469Y0072564*
X069358Y0072494*
X0693691Y0072425*
X0693719Y0072411*
X0693775Y0072355*
X0693858Y0072258*
X0693941Y0072147*
X0694038Y0071995*
X0694122Y0071828*
X0694177Y0071634*
X0694205Y0071412*
Y0071384*
Y0071328*
X0694191Y0071231*
X0694163Y007112*
X0694122Y0070981*
X0694052Y0070842*
X0693969Y0070704*
X0693844Y0070565*
X069383Y0070551*
X0693761Y0070509*
X0693705Y0070468*
X069365Y007044*
X0693567Y0070398*
X0693469Y0070343*
X0693344Y0070301*
X0693206Y0070246*
X0693053Y007019*
X0692873Y0070121*
X0692678Y0070065*
X0692456Y0069996*
X0692206Y006994*
X0691929Y0069871*
X0691915*
X0691859Y0069857*
X0691776Y0069843*
X0691679Y0069815*
X0691554Y0069788*
X0691401Y0069746*
X0691249Y0069704*
X0691082Y0069663*
X0690721Y0069565*
X0690374Y0069468*
X0690208Y0069413*
X0690055Y0069357*
X0689916Y0069316*
X0689805Y006926*
X0689791*
X0689763Y0069246*
X0689722Y0069218*
X0689666Y0069191*
X0689514Y0069107*
X0689333Y0068996*
X0689125Y0068844*
X0688917Y0068677*
X0688723Y0068483*
X0688556Y0068275*
X0688542Y0068247*
X0688486Y0068177*
X0688431Y0068053*
X0688348Y0067886*
X0688278Y0067692*
X0688209Y0067456*
X0688167Y0067192*
X0688153Y0066914*
Y006679*
X0688181Y0066637*
X0688209Y0066443*
X0688264Y006622*
X0688334Y0065984*
X0688445Y0065735*
X0688598Y0065471*
Y0065457*
X0688611Y0065443*
X0688681Y006536*
X0688778Y0065235*
X0688917Y0065096*
X0689097Y006493*
X0689319Y0064749*
X0689569Y0064583*
X0689861Y006443*
X0689875*
X0689902Y0064416*
X0689944Y0064402*
X0689999Y0064374*
X0690083Y0064347*
X069018Y0064305*
X0690402Y0064249*
X0690666Y006418*
X0690985Y0064111*
X0691332Y0064069*
X0691707Y0064055*
X0691929*
X069204Y0064069*
X0692165*
X0692304Y0064083*
X069247Y0064097*
X0692817Y0064152*
X0693178Y0064208*
X0693539Y0064305*
X0693886Y006443*
X06939*
X0693927Y0064444*
X0693969Y0064472*
X0694025Y0064499*
X0694191Y0064583*
X0694385Y0064707*
X0694608Y0064874*
X0694844Y0065068*
X0695066Y0065304*
X0695274Y0065568*
Y0065582*
X0695302Y006561*
X0695316Y0065651*
X0695357Y0065707*
X0695385Y0065776*
X0695427Y006586*
X0695524Y0066068*
X0695621Y0066331*
X0695704Y0066623*
X069576Y0066956*
X0695787Y0067303*
X0694594Y0067414*
Y00674*
Y0067386*
X069458Y0067345*
Y0067289*
X0694552Y0067164*
X069451Y0066984*
X0694455Y0066803*
X0694399Y0066595*
X0694302Y0066401*
X0694205Y006622*
X0694191Y0066207*
X069415Y0066151*
X069408Y0066054*
X0693969Y0065957*
X069383Y0065832*
X0693678Y0065707*
X0693469Y0065582*
X0693247Y0065471*
X0693233*
X069322Y0065457*
X0693178Y0065443*
X0693136Y0065429*
X0692998Y0065388*
X0692817Y0065332*
X0692595Y0065277*
X0692345Y0065235*
X0692068Y0065207*
X0691762Y0065193*
X0691637*
X0691499Y0065207*
X0691332Y0065221*
X0691138Y0065249*
X0690915Y0065277*
X0690693Y0065332*
X0690485Y0065402*
X0690457Y0065415*
X0690388Y0065443*
X0690291Y0065499*
X0690166Y0065554*
X0690041Y0065651*
X0689902Y0065749*
X0689763Y006586*
X0689652Y0065998*
X0689639Y0066012*
X0689611Y0066068*
X0689569Y0066137*
X0689514Y0066248*
X0689458Y0066359*
X0689417Y0066498*
X0689389Y0066651*
X0689375Y0066817*
Y0066831*
Y00669*
X0689389Y0066984*
X0689403Y0067095*
X0689444Y0067206*
X0689486Y0067345*
X0689555Y0067484*
X0689652Y0067608*
X0689666Y0067622*
X0689708Y0067664*
X0689763Y0067719*
X0689861Y0067803*
X0689972Y0067886*
X0690124Y0067983*
X0690305Y006808*
X0690513Y0068164*
X0690527Y0068177*
X0690596Y0068191*
X0690707Y0068233*
X0690777Y0068247*
X0690874Y0068275*
X0690971Y0068316*
X0691096Y0068344*
X0691235Y0068386*
X0691401Y0068427*
X0691568Y0068469*
X0691762Y0068524*
X0691984Y006858*
X069222Y0068635*
X0692234*
X0692276Y0068649*
X0692345Y0068663*
X0692428Y0068691*
X069254Y0068719*
X0692664Y0068747*
X0692942Y006883*
X0693247Y0068927*
X0693567Y0069024*
X0693844Y0069121*
X0693969Y0069177*
X069408Y0069232*
X0694094*
X0694108Y0069246*
X0694191Y0069302*
X0694316Y0069371*
X0694455Y0069482*
X0694622Y0069607*
X0694788Y006976*
X0694955Y006994*
X0695093Y0070135*
X0695107Y0070162*
X0695149Y0070232*
X0695204Y0070343*
X069526Y0070482*
X0695316Y0070662*
X0695371Y007087*
X0695413Y0071092*
X0695427Y0071328*
Y0071342*
Y0071356*
Y0071398*
Y0071453*
X0695399Y0071592*
X0695371Y0071772*
X0695329Y0071981*
X069526Y0072217*
X0695163Y0072452*
X0695024Y0072689*
Y0072702*
X069501Y0072716*
X0694941Y0072799*
X0694844Y0072911*
X0694719Y0073049*
X0694552Y0073202*
X0694344Y0073369*
X0694094Y0073521*
X0693816Y007366*
X0693803*
X0693775Y0073674*
X0693733Y0073688*
X0693678Y0073716*
X0693608Y0073743*
X0693511Y0073771*
X0693303Y0073827*
X0693039Y0073882*
X0692734Y0073938*
X0692415Y0073979*
X0692054Y0073993*
G37*
%LNtimecard-dc-beta-v1-3*%
%LPD*%
G54D21*
X0305034Y0046108D02*
X0305534Y0045608D01*
Y0044608*
X0305034Y0044108*
X0303035*
X0302535Y0044608*
Y0045608*
X0303035Y0046108*
X0305534Y0049107D02*
Y0047107D01*
X0304034*
X0304534Y0048107*
Y0048607*
X0304034Y0049107*
X0303035*
X0302535Y0048607*
Y0047607*
X0303035Y0047107*
X0305034Y0050106D02*
X0305534Y0050606D01*
Y0051606*
X0305034Y0052106*
X0304534*
X0304034Y0051606*
Y0051106*
Y0051606*
X0303535Y0052106*
X0303035*
X0302535Y0051606*
Y0050606*
X0303035Y0050106*
X0298434Y0046108D02*
X0298934Y0045608D01*
Y0044608*
X0298434Y0044108*
X0296435*
X0295935Y0044608*
Y0045608*
X0296435Y0046108*
X0298934Y0049107D02*
Y0047107D01*
X0297434*
X0297934Y0048107*
Y0048607*
X0297434Y0049107*
X0296435*
X0295935Y0048607*
Y0047607*
X0296435Y0047107*
X0295935Y0052106D02*
Y0050106D01*
X0297934Y0052106*
X0298434*
X0298934Y0051606*
Y0050606*
X0298434Y0050106*
X0288934Y0046108D02*
X0289434Y0045608D01*
Y0044608*
X0288934Y0044108*
X0286935*
X0286435Y0044608*
Y0045608*
X0286935Y0046108*
X0289434Y0049107D02*
Y0047107D01*
X0287934*
X0288434Y0048107*
Y0048607*
X0287934Y0049107*
X0286935*
X0286435Y0048607*
Y0047607*
X0286935Y0047107*
X0286435Y0050106D02*
Y0051106D01*
Y0050606*
X0289434*
X0288934Y0050106*
X0281834Y0046108D02*
X0282334Y0045608D01*
Y0044608*
X0281834Y0044108*
X0279835*
X0279335Y0044608*
Y0045608*
X0279835Y0046108*
X0282334Y0049107D02*
Y0047107D01*
X0280835*
X0281334Y0048107*
Y0048607*
X0280835Y0049107*
X0279835*
X0279335Y0048607*
Y0047607*
X0279835Y0047107*
X0281834Y0050106D02*
X0282334Y0050606D01*
Y0051606*
X0281834Y0052106*
X0279835*
X0279335Y0051606*
Y0050606*
X0279835Y0050106*
X0281834*
X0272734Y0046108D02*
X0273234Y0045608D01*
Y0044608*
X0272734Y0044108*
X0270735*
X0270235Y0044608*
Y0045608*
X0270735Y0046108*
X0270235Y0048607D02*
X0273234D01*
X0271734Y0047107*
Y0049107*
X0270735Y0050106D02*
X0270235Y0050606D01*
Y0051606*
X0270735Y0052106*
X0272734*
X0273234Y0051606*
Y0050606*
X0272734Y0050106*
X0272234*
X0271734Y0050606*
Y0052106*
X0265934Y0046108D02*
X0266434Y0045608D01*
Y0044608*
X0265934Y0044108*
X0263935*
X0263435Y0044608*
Y0045608*
X0263935Y0046108*
X0263435Y0048607D02*
X0266434D01*
X0264934Y0047107*
Y0049107*
X0265934Y0050106D02*
X0266434Y0050606D01*
Y0051606*
X0265934Y0052106*
X0265434*
X0264934Y0051606*
X0264435Y0052106*
X0263935*
X0263435Y0051606*
Y0050606*
X0263935Y0050106*
X0264435*
X0264934Y0050606*
X0265434Y0050106*
X0265934*
X0264934Y0050606D02*
Y0051606D01*
X0254434Y0046108D02*
X0254934Y0045608D01*
Y0044608*
X0254434Y0044108*
X0252435*
X0251935Y0044608*
Y0045608*
X0252435Y0046108*
X0251935Y0048607D02*
X0254934D01*
X0253434Y0047107*
Y0049107*
X0254934Y0050106D02*
Y0052106D01*
X0254434*
X0252435Y0050106*
X0251935*
X0247534Y0046108D02*
X0248034Y0045608D01*
Y0044608*
X0247534Y0044108*
X0245535*
X0245035Y0044608*
Y0045608*
X0245535Y0046108*
X0245035Y0048607D02*
X0248034D01*
X0246534Y0047107*
Y0049107*
X0248034Y0052106D02*
X0247534Y0051106D01*
X0246534Y0050106*
X0245535*
X0245035Y0050606*
Y0051606*
X0245535Y0052106*
X0246035*
X0246534Y0051606*
Y0050106*
X0240098Y0047767D02*
X0240597Y0047267D01*
Y0046268*
X0240098Y0045768*
X0238098*
X0237598Y0046268*
Y0047267*
X0238098Y0047767*
X0237598Y0050266D02*
X0240597D01*
X0239098Y0048767*
Y0050766*
X0240597Y0053765D02*
Y0051766D01*
X0239098*
X0239598Y0052766*
Y0053265*
X0239098Y0053765*
X0238098*
X0237598Y0053265*
Y0052266*
X0238098Y0051766*
X0233109Y0047964D02*
X0233609Y0047464D01*
Y0046464*
X0233109Y0045965*
X023111*
X023061Y0046464*
Y0047464*
X023111Y0047964*
X023061Y0050463D02*
X0233609D01*
X023211Y0048964*
Y0050963*
X023061Y0053462D02*
X0233609D01*
X023211Y0051963*
Y0053962*
G54D136*
X0604921Y0069882D03*
M02*